# T6G (Grand Teton) — schematic netlist excerpt (pin names and nets, part order shuffled) for the footprints in the layout excerpt that follows; sources: Cadence DE-HDL packaged netlist, KiCad conversion of 04192023_DAF0TMB3IC0_F0TG_MB_C_brd_V02_OCP.brd

PC331_1  Q_CAP  22UF 16V 20% X6S  pkg C0805  page 215 : A = SW_P12V_AUX_PVDDCR_SOC_P1_FLT ; B = GND
C2308  Q_CAP  22UF 4V 20% X6S  pkg C0402  page 73 : A = PVDDCR_CPU0_P1 ; B = GND
C2432  Q_CAP  22UF 4V 20% X6S  pkg C0402  page 74 : A = PVDDCR_SOC_P1 ; B = GND

(kicad_pcb
	(version 20260206)
	(generator "pcbnew")
	(generator_version "10.0")
	(general
		(thickness 1.6)
		(legacy_teardrops no)
	)
	(paper "A4")
	(title_block
		(title "04192023_DAF0TMB3IC0_F0TG_MB_C_brd_V02_OCP.brd")
		(comment 1 "Grand Teton / footprints 5193-5195 of 8354")
	)
	(layers
		(0 "F.Cu" signal "TOP")
		(4 "In1.Cu" signal "GND")
		(6 "In2.Cu" signal "IN1")
		(8 "In3.Cu" signal "GND1")
		(10 "In4.Cu" signal "IN2")
		(12 "In5.Cu" signal "GND2")
		(14 "In6.Cu" signal "IN3")
		(16 "In7.Cu" signal "GND3")
		(18 "In8.Cu" signal "VCC")
		(20 "In9.Cu" signal "VCC1")
		(22 "In10.Cu" signal "GND4")
		(24 "In11.Cu" signal "IN4")
		(26 "In12.Cu" signal "GND5")
		(28 "In13.Cu" signal "IN5")
		(30 "In14.Cu" signal "GND6")
		(32 "In15.Cu" signal "IN6")
		(34 "In16.Cu" signal "GND7")
		(2 "B.Cu" signal "BOTTOM")
		(9 "F.Adhes" user "F.Adhesive")
		(11 "B.Adhes" user "B.Adhesive")
		(13 "F.Paste" user "Package Geometry/Pastemask Top")
		(15 "B.Paste" user "Package Geometry/Pastemask Bottom")
		(5 "F.SilkS" user "Ref Des/Silkscreen Top")
		(7 "B.SilkS" user "Ref Des/Silkscreen Bottom")
		(1 "F.Mask" user "Board Geometry/Soldermask Top")
		(3 "B.Mask" user "Board Geometry/Soldermask Bottom")
		(17 "Dwgs.User" user "User.Drawings")
		(19 "Cmts.User" user "User.Comments")
		(21 "Eco1.User" user "User.Eco1")
		(23 "Eco2.User" user "User.Eco2")
		(25 "Edge.Cuts" user "Board Geometry/Outline")
		(27 "Margin" user)
		(31 "F.CrtYd" user "Package Geometry/Place Bound Top")
		(29 "B.CrtYd" user "Package Geometry/Place Bound Bottom")
		(35 "F.Fab" user "Ref Des/Assembly Top")
		(33 "B.Fab" user "Ref Des/Assembly Bottom")
	)
	(footprint ""
		(layer "B.Cu")
		(at 112.550448 -171.785534 -90)
		(property "Reference" "PC331_1"
			(at 0 0 90)
			(layer "B.SilkS")
			(hide yes)
			(effects
				(font
					(size 1.27 1.27)
				)
				(justify mirror)
			)
		)
		(property "Value" ""
			(at 0 0 90)
			(layer "B.Fab")
			(effects
				(font
					(size 1.27 1.27)
				)
				(justify mirror)
			)
		)
		(duplicate_pad_numbers_are_jumpers no)
		(fp_line
			(start -1.524 0.762)
			(end 1.524 0.762)
			(stroke
				(width 0.1524)
				(type default)
			)
			(layer "B.SilkS")
		)
		(fp_line
			(start 1.524 0.762)
			(end 1.524 -0.762)
			(stroke
				(width 0.1524)
				(type default)
			)
			(layer "B.SilkS")
		)
		(fp_line
			(start -1.524 -0.762)
			(end -1.524 0.762)
			(stroke
				(width 0.1524)
				(type default)
			)
			(layer "B.SilkS")
		)
		(fp_line
			(start 1.524 -0.762)
			(end -1.524 -0.762)
			(stroke
				(width 0.1524)
				(type default)
			)
			(layer "B.SilkS")
		)
		(fp_line
			(start -1.1049 0.724916)
			(end -1.1049 -0.724916)
			(stroke
				(width 0.1)
				(type default)
			)
			(layer "B.Fab")
		)
		(fp_line
			(start 1.1049 0.724916)
			(end -1.1049 0.724916)
			(stroke
				(width 0.1)
				(type default)
			)
			(layer "B.Fab")
		)
		(fp_line
			(start -1.1049 -0.724916)
			(end 1.1049 -0.724916)
			(stroke
				(width 0.1)
				(type default)
			)
			(layer "B.Fab")
		)
		(fp_line
			(start 1.1049 -0.724916)
			(end 1.1049 0.724916)
			(stroke
				(width 0.1)
				(type default)
			)
			(layer "B.Fab")
		)
		(pad "1" smd rect
			(at 0.889 0 270)
			(size 1.016 1.27)
			(layers "B.Cu" "B.Mask" "B.Paste")
			(net "SW_P12V_AUX_PVDDCR_SOC_P1_FLT")
		)
		(pad "2" smd rect
			(at -0.889 0 270)
			(size 1.016 1.27)
			(layers "B.Cu" "B.Mask" "B.Paste")
			(net "GND")
		)
	)
	(footprint ""
		(layer "B.Cu")
		(at 107.129834 -245.487952 180)
		(property "Reference" "C2308"
			(at 0 0 0)
			(layer "B.SilkS")
			(hide yes)
			(effects
				(font
					(size 1.27 1.27)
				)
				(justify mirror)
			)
		)
		(property "Value" ""
			(at 0 0 0)
			(layer "B.Fab")
			(effects
				(font
					(size 1.27 1.27)
				)
				(justify mirror)
			)
		)
		(duplicate_pad_numbers_are_jumpers no)
		(fp_line
			(start 0.7874 0.4064)
			(end 0.7874 -0.4064)
			(stroke
				(width 0.1524)
				(type default)
			)
			(layer "B.SilkS")
		)
		(fp_line
			(start 0.7874 -0.4064)
			(end -0.7874 -0.4064)
			(stroke
				(width 0.1524)
				(type default)
			)
			(layer "B.SilkS")
		)
		(fp_line
			(start -0.7874 0.4064)
			(end 0.7874 0.4064)
			(stroke
				(width 0.1524)
				(type default)
			)
			(layer "B.SilkS")
		)
		(fp_line
			(start -0.7874 -0.4064)
			(end -0.7874 0.4064)
			(stroke
				(width 0.1524)
				(type default)
			)
			(layer "B.SilkS")
		)
		(fp_line
			(start 0.67945 0.3048)
			(end 0.67945 -0.305054)
			(stroke
				(width 0.1)
				(type default)
			)
			(layer "B.Fab")
		)
		(fp_line
			(start 0.67945 -0.305054)
			(end 0.12065 -0.305054)
			(stroke
				(width 0.1)
				(type default)
			)
			(layer "B.Fab")
		)
		(fp_line
			(start 0.12065 0.3048)
			(end 0.67945 0.3048)
			(stroke
				(width 0.1)
				(type default)
			)
			(layer "B.Fab")
		)
		(fp_line
			(start 0.12065 0.2794)
			(end 0.12065 0.3048)
			(stroke
				(width 0.1)
				(type default)
			)
			(layer "B.Fab")
		)
		(fp_line
			(start 0.12065 -0.2794)
			(end -0.12065 -0.2794)
			(stroke
				(width 0.1)
				(type default)
			)
			(layer "B.Fab")
		)
		(fp_line
			(start 0.12065 -0.305054)
			(end 0.12065 -0.2794)
			(stroke
				(width 0.1)
				(type default)
			)
			(layer "B.Fab")
		)
		(fp_line
			(start -0.120396 0.3048)
			(end -0.120396 0.2794)
			(stroke
				(width 0.1)
				(type default)
			)
			(layer "B.Fab")
		)
		(fp_line
			(start -0.120396 0.2794)
			(end 0.12065 0.2794)
			(stroke
				(width 0.1)
				(type default)
			)
			(layer "B.Fab")
		)
		(fp_line
			(start -0.12065 -0.2794)
			(end -0.12065 -0.3048)
			(stroke
				(width 0.1)
				(type default)
			)
			(layer "B.Fab")
		)
		(fp_line
			(start -0.12065 -0.3048)
			(end -0.67945 -0.3048)
			(stroke
				(width 0.1)
				(type default)
			)
			(layer "B.Fab")
		)
		(fp_line
			(start -0.67945 0.3048)
			(end -0.120396 0.3048)
			(stroke
				(width 0.1)
				(type default)
			)
			(layer "B.Fab")
		)
		(fp_line
			(start -0.67945 -0.3048)
			(end -0.67945 0.3048)
			(stroke
				(width 0.1)
				(type default)
			)
			(layer "B.Fab")
		)
		(pad "1" smd circle
			(at 0.40005 0)
			(size 0 0)
			(layers "B.Cu" "B.Mask" "B.Paste")
			(net "PVDDCR_CPU0_P1")
		)
		(pad "2" smd circle
			(at -0.40005 0)
			(size 0 0)
			(layers "B.Cu" "B.Mask" "B.Paste")
			(net "GND")
		)
	)
	(footprint ""
		(layer "B.Cu")
		(at 123.611386 -259.73024)
		(property "Reference" "C2432"
			(at 0 0 0)
			(layer "B.SilkS")
			(hide yes)
			(effects
				(font
					(size 1.27 1.27)
				)
				(justify mirror)
			)
		)
		(property "Value" ""
			(at 0 0 0)
			(layer "B.Fab")
			(effects
				(font
					(size 1.27 1.27)
				)
				(justify mirror)
			)
		)
		(duplicate_pad_numbers_are_jumpers no)
		(fp_line
			(start -0.7874 -0.4064)
			(end -0.7874 0.4064)
			(stroke
				(width 0.1524)
				(type default)
			)
			(layer "B.SilkS")
		)
		(fp_line
			(start -0.7874 0.4064)
			(end 0.7874 0.4064)
			(stroke
				(width 0.1524)
				(type default)
			)
			(layer "B.SilkS")
		)
		(fp_line
			(start 0.7874 -0.4064)
			(end -0.7874 -0.4064)
			(stroke
				(width 0.1524)
				(type default)
			)
			(layer "B.SilkS")
		)
		(fp_line
			(start 0.7874 0.4064)
			(end 0.7874 -0.4064)
			(stroke
				(width 0.1524)
				(type default)
			)
			(layer "B.SilkS")
		)
		(fp_line
			(start -0.67945 -0.3048)
			(end -0.67945 0.3048)
			(stroke
				(width 0.1)
				(type default)
			)
			(layer "B.Fab")
		)
		(fp_line
			(start -0.67945 0.3048)
			(end -0.120396 0.3048)
			(stroke
				(width 0.1)
				(type default)
			)
			(layer "B.Fab")
		)
		(fp_line
			(start -0.12065 -0.3048)
			(end -0.67945 -0.3048)
			(stroke
				(width 0.1)
				(type default)
			)
			(layer "B.Fab")
		)
		(fp_line
			(start -0.12065 -0.2794)
			(end -0.12065 -0.3048)
			(stroke
				(width 0.1)
				(type default)
			)
			(layer "B.Fab")
		)
		(fp_line
			(start -0.120396 0.2794)
			(end 0.12065 0.2794)
			(stroke
				(width 0.1)
				(type default)
			)
			(layer "B.Fab")
		)
		(fp_line
			(start -0.120396 0.3048)
			(end -0.120396 0.2794)
			(stroke
				(width 0.1)
				(type default)
			)
			(layer "B.Fab")
		)
		(fp_line
			(start 0.12065 -0.305054)
			(end 0.12065 -0.2794)
			(stroke
				(width 0.1)
				(type default)
			)
			(layer "B.Fab")
		)
		(fp_line
			(start 0.12065 -0.2794)
			(end -0.12065 -0.2794)
			(stroke
				(width 0.1)
				(type default)
			)
			(layer "B.Fab")
		)
		(fp_line
			(start 0.12065 0.2794)
			(end 0.12065 0.3048)
			(stroke
				(width 0.1)
				(type default)
			)
			(layer "B.Fab")
		)
		(fp_line
			(start 0.12065 0.3048)
			(end 0.67945 0.3048)
			(stroke
				(width 0.1)
				(type default)
			)
			(layer "B.Fab")
		)
		(fp_line
			(start 0.67945 -0.305054)
			(end 0.12065 -0.305054)
			(stroke
				(width 0.1)
				(type default)
			)
			(layer "B.Fab")
		)
		(fp_line
			(start 0.67945 0.3048)
			(end 0.67945 -0.305054)
			(stroke
				(width 0.1)
				(type default)
			)
			(layer "B.Fab")
		)
		(pad "1" smd circle
			(at 0.40005 0 180)
			(size 0 0)
			(layers "B.Cu" "B.Mask" "B.Paste")
			(net "PVDDCR_SOC_P1")
		)
		(pad "2" smd circle
			(at -0.40005 0 180)
			(size 0 0)
			(layers "B.Cu" "B.Mask" "B.Paste")
			(net "GND")
		)
	)
)
